# S9S_MB_2U (Grand Teton) — schematic netlist excerpt (pin names and nets, part order shuffled) for the footprints in the layout excerpt that follows; sources: Cadence DE-HDL packaged netlist, KiCad conversion of 03242023_DA0F0TMBIJ0_F0T_Motherboard_J_brd_V01_OCP.brd

R2308  Q_RES  10K 1% EMPTY  pkg 0402LF  page 236 : A = P3V3_AUX ; B = PCA9543_S3M_ADDR1
R1132  Q_RES  1K 1% EMPTY  pkg 0402LF  page 164 : A = P3V3_AUX ; B = HP_OCP_V3_2_RST_R

(kicad_pcb
	(version 20260206)
	(generator "pcbnew")
	(generator_version "10.0")
	(general
		(thickness 1.6)
		(legacy_teardrops no)
	)
	(paper "A4")
	(title_block
		(title "03242023_DA0F0TMBIJ0_F0T_Motherboard_J_brd_V01_OCP.brd")
		(comment 1 "Grand Teton / footprints 2896-2897 of 6105")
	)
	(layers
		(0 "F.Cu" signal "TOP")
		(4 "In1.Cu" signal "GND")
		(6 "In2.Cu" signal "IN1")
		(8 "In3.Cu" signal "GND1")
		(10 "In4.Cu" signal "IN2")
		(12 "In5.Cu" signal "GND2")
		(14 "In6.Cu" signal "IN3")
		(16 "In7.Cu" signal "GND3")
		(18 "In8.Cu" signal "VCC")
		(20 "In9.Cu" signal "VCC1")
		(22 "In10.Cu" signal "GND4")
		(24 "In11.Cu" signal "IN4")
		(26 "In12.Cu" signal "GND5")
		(28 "In13.Cu" signal "IN5")
		(30 "In14.Cu" signal "GND6")
		(32 "In15.Cu" signal "IN6")
		(34 "In16.Cu" signal "GND7")
		(2 "B.Cu" signal "BOTTOM")
		(9 "F.Adhes" user "F.Adhesive")
		(11 "B.Adhes" user "B.Adhesive")
		(13 "F.Paste" user "Package Geometry/Pastemask Top")
		(15 "B.Paste" user "Package Geometry/Pastemask Bottom")
		(5 "F.SilkS" user "Ref Des/Silkscreen Top")
		(7 "B.SilkS" user "Ref Des/Silkscreen Bottom")
		(1 "F.Mask" user "Board Geometry/Soldermask Top")
		(3 "B.Mask" user "Board Geometry/Soldermask Bottom")
		(17 "Dwgs.User" user "User.Drawings")
		(19 "Cmts.User" user "User.Comments")
		(21 "Eco1.User" user "User.Eco1")
		(23 "Eco2.User" user "User.Eco2")
		(25 "Edge.Cuts" user "Board Geometry/Outline")
		(27 "Margin" user)
		(31 "F.CrtYd" user "Package Geometry/Place Bound Top")
		(29 "B.CrtYd" user "Package Geometry/Place Bound Bottom")
		(35 "F.Fab" user "Ref Des/Assembly Top")
		(33 "B.Fab" user "Ref Des/Assembly Bottom")
	)
	(footprint ""
		(layer "F.Cu")
		(at 85.9028 -36.032948 180)
		(property "Reference" "R1132"
			(at 0 0 180)
			(layer "F.SilkS")
			(hide yes)
			(effects
				(font
					(size 1.27 1.27)
				)
			)
		)
		(property "Value" ""
			(at 0 0 180)
			(layer "F.Fab")
			(effects
				(font
					(size 1.27 1.27)
				)
			)
		)
		(duplicate_pad_numbers_are_jumpers no)
		(fp_line
			(start 0.7874 0.4064)
			(end -0.7874 0.4064)
			(stroke
				(width 0.1524)
				(type default)
			)
			(layer "F.SilkS")
		)
		(fp_line
			(start 0.7874 -0.4064)
			(end 0.7874 0.4064)
			(stroke
				(width 0.1524)
				(type default)
			)
			(layer "F.SilkS")
		)
		(fp_line
			(start -0.7874 0.4064)
			(end -0.7874 -0.4064)
			(stroke
				(width 0.1524)
				(type default)
			)
			(layer "F.SilkS")
		)
		(fp_line
			(start -0.7874 -0.4064)
			(end 0.7874 -0.4064)
			(stroke
				(width 0.1524)
				(type default)
			)
			(layer "F.SilkS")
		)
		(fp_line
			(start 0.67945 0.3048)
			(end 0.120396 0.3048)
			(stroke
				(width 0.1)
				(type default)
			)
			(layer "F.Fab")
		)
		(fp_line
			(start 0.67945 -0.3048)
			(end 0.67945 0.3048)
			(stroke
				(width 0.1)
				(type default)
			)
			(layer "F.Fab")
		)
		(fp_line
			(start 0.12065 -0.2794)
			(end 0.12065 -0.3048)
			(stroke
				(width 0.1)
				(type default)
			)
			(layer "F.Fab")
		)
		(fp_line
			(start 0.12065 -0.3048)
			(end 0.67945 -0.3048)
			(stroke
				(width 0.1)
				(type default)
			)
			(layer "F.Fab")
		)
		(fp_line
			(start 0.120396 0.3048)
			(end 0.120396 0.2794)
			(stroke
				(width 0.1)
				(type default)
			)
			(layer "F.Fab")
		)
		(fp_line
			(start 0.120396 0.2794)
			(end -0.12065 0.2794)
			(stroke
				(width 0.1)
				(type default)
			)
			(layer "F.Fab")
		)
		(fp_line
			(start -0.12065 0.3048)
			(end -0.67945 0.3048)
			(stroke
				(width 0.1)
				(type default)
			)
			(layer "F.Fab")
		)
		(fp_line
			(start -0.12065 0.2794)
			(end -0.12065 0.3048)
			(stroke
				(width 0.1)
				(type default)
			)
			(layer "F.Fab")
		)
		(fp_line
			(start -0.12065 -0.2794)
			(end 0.12065 -0.2794)
			(stroke
				(width 0.1)
				(type default)
			)
			(layer "F.Fab")
		)
		(fp_line
			(start -0.12065 -0.305054)
			(end -0.12065 -0.2794)
			(stroke
				(width 0.1)
				(type default)
			)
			(layer "F.Fab")
		)
		(fp_line
			(start -0.67945 0.3048)
			(end -0.67945 -0.305054)
			(stroke
				(width 0.1)
				(type default)
			)
			(layer "F.Fab")
		)
		(fp_line
			(start -0.67945 -0.305054)
			(end -0.12065 -0.305054)
			(stroke
				(width 0.1)
				(type default)
			)
			(layer "F.Fab")
		)
		(pad "1" smd circle
			(at -0.40005 0 180)
			(size 0 0)
			(layers "F.Cu" "F.Mask" "F.Paste")
			(net "P3V3_AUX")
		)
		(pad "2" smd circle
			(at 0.40005 0 180)
			(size 0 0)
			(layers "F.Cu" "F.Mask" "F.Paste")
			(net "HP_OCP_V3_2_RST_R")
		)
	)
	(footprint ""
		(layer "F.Cu")
		(at 154.65933 -70.26402 90)
		(property "Reference" "R2308"
			(at 0 0 90)
			(layer "F.SilkS")
			(hide yes)
			(effects
				(font
					(size 1.27 1.27)
				)
			)
		)
		(property "Value" ""
			(at 0 0 90)
			(layer "F.Fab")
			(effects
				(font
					(size 1.27 1.27)
				)
			)
		)
		(duplicate_pad_numbers_are_jumpers no)
		(fp_line
			(start 0.7874 -0.4064)
			(end 0.7874 0.4064)
			(stroke
				(width 0.1524)
				(type default)
			)
			(layer "F.SilkS")
		)
		(fp_line
			(start -0.7874 -0.4064)
			(end 0.7874 -0.4064)
			(stroke
				(width 0.1524)
				(type default)
			)
			(layer "F.SilkS")
		)
		(fp_line
			(start 0.7874 0.4064)
			(end -0.7874 0.4064)
			(stroke
				(width 0.1524)
				(type default)
			)
			(layer "F.SilkS")
		)
		(fp_line
			(start -0.7874 0.4064)
			(end -0.7874 -0.4064)
			(stroke
				(width 0.1524)
				(type default)
			)
			(layer "F.SilkS")
		)
		(fp_line
			(start -0.12065 -0.305054)
			(end -0.12065 -0.2794)
			(stroke
				(width 0.1)
				(type default)
			)
			(layer "F.Fab")
		)
		(fp_line
			(start -0.67945 -0.305054)
			(end -0.12065 -0.305054)
			(stroke
				(width 0.1)
				(type default)
			)
			(layer "F.Fab")
		)
		(fp_line
			(start 0.67945 -0.3048)
			(end 0.67945 0.3048)
			(stroke
				(width 0.1)
				(type default)
			)
			(layer "F.Fab")
		)
		(fp_line
			(start 0.12065 -0.3048)
			(end 0.67945 -0.3048)
			(stroke
				(width 0.1)
				(type default)
			)
			(layer "F.Fab")
		)
		(fp_line
			(start 0.12065 -0.2794)
			(end 0.12065 -0.3048)
			(stroke
				(width 0.1)
				(type default)
			)
			(layer "F.Fab")
		)
		(fp_line
			(start -0.12065 -0.2794)
			(end 0.12065 -0.2794)
			(stroke
				(width 0.1)
				(type default)
			)
			(layer "F.Fab")
		)
		(fp_line
			(start 0.120396 0.2794)
			(end -0.12065 0.2794)
			(stroke
				(width 0.1)
				(type default)
			)
			(layer "F.Fab")
		)
		(fp_line
			(start -0.12065 0.2794)
			(end -0.12065 0.3048)
			(stroke
				(width 0.1)
				(type default)
			)
			(layer "F.Fab")
		)
		(fp_line
			(start 0.67945 0.3048)
			(end 0.120396 0.3048)
			(stroke
				(width 0.1)
				(type default)
			)
			(layer "F.Fab")
		)
		(fp_line
			(start 0.120396 0.3048)
			(end 0.120396 0.2794)
			(stroke
				(width 0.1)
				(type default)
			)
			(layer "F.Fab")
		)
		(fp_line
			(start -0.12065 0.3048)
			(end -0.67945 0.3048)
			(stroke
				(width 0.1)
				(type default)
			)
			(layer "F.Fab")
		)
		(fp_line
			(start -0.67945 0.3048)
			(end -0.67945 -0.305054)
			(stroke
				(width 0.1)
				(type default)
			)
			(layer "F.Fab")
		)
		(pad "1" smd circle
			(at -0.40005 0 90)
			(size 0 0)
			(layers "F.Cu" "F.Mask" "F.Paste")
			(net "P3V3_AUX")
		)
		(pad "2" smd circle
			(at 0.40005 0 90)
			(size 0 0)
			(layers "F.Cu" "F.Mask" "F.Paste")
			(net "PCA9543_S3M_ADDR1")
		)
	)
)
